(kicad_pcb
	(version 20260206)
	(generator "pcbnew")
	(generator_version "10.0")
	(general
		(thickness 1.6)
		(legacy_teardrops no)
	)
	(paper "A4")
	(title_block
		(title "03242023_DA0F0TMBIJ0_F0T_Motherboard_J_brd_V01_OCP.brd")
		(comment 1 "Grand Teton / footprints 5118-5123 of 6105")
	)
	(layers
		(0 "F.Cu" signal "TOP")
		(4 "In1.Cu" signal "GND")
		(6 "In2.Cu" signal "IN1")
		(8 "In3.Cu" signal "GND1")
		(10 "In4.Cu" signal "IN2")
		(12 "In5.Cu" signal "GND2")
		(14 "In6.Cu" signal "IN3")
		(16 "In7.Cu" signal "GND3")
		(18 "In8.Cu" signal "VCC")
		(20 "In9.Cu" signal "VCC1")
		(22 "In10.Cu" signal "GND4")
		(24 "In11.Cu" signal "IN4")
		(26 "In12.Cu" signal "GND5")
		(28 "In13.Cu" signal "IN5")
		(30 "In14.Cu" signal "GND6")
		(32 "In15.Cu" signal "IN6")
		(34 "In16.Cu" signal "GND7")
		(2 "B.Cu" signal "BOTTOM")
		(9 "F.Adhes" user "F.Adhesive")
		(11 "B.Adhes" user "B.Adhesive")
		(13 "F.Paste" user "Package Geometry/Pastemask Top")
		(15 "B.Paste" user "Package Geometry/Pastemask Bottom")
		(5 "F.SilkS" user "Ref Des/Silkscreen Top")
		(7 "B.SilkS" user "Ref Des/Silkscreen Bottom")
		(1 "F.Mask" user "Board Geometry/Soldermask Top")
		(3 "B.Mask" user "Board Geometry/Soldermask Bottom")
		(17 "Dwgs.User" user "User.Drawings")
		(19 "Cmts.User" user "User.Comments")
		(21 "Eco1.User" user "User.Eco1")
		(23 "Eco2.User" user "User.Eco2")
		(25 "Edge.Cuts" user "Board Geometry/Outline")
		(27 "Margin" user)
		(31 "F.CrtYd" user "Package Geometry/Place Bound Top")
		(29 "B.CrtYd" user "Package Geometry/Place Bound Bottom")
		(35 "F.Fab" user "Ref Des/Assembly Top")
		(33 "B.Fab" user "Ref Des/Assembly Bottom")
	)
	(footprint ""
		(layer "B.Cu")
		(at 175.281082 -353.726242 90)
		(property "Reference" "PC405_P1_1"
			(at 0 0 90)
			(layer "B.SilkS")
			(hide yes)
			(effects
				(font
					(size 1.27 1.27)
				)
				(justify mirror)
			)
		)
		(property "Value" ""
			(at 0 0 90)
			(layer "B.Fab")
			(effects
				(font
					(size 1.27 1.27)
				)
				(justify mirror)
			)
		)
		(duplicate_pad_numbers_are_jumpers no)
		(fp_line
			(start 1.524 -0.762)
			(end -1.524 -0.762)
			(stroke
				(width 0.1524)
				(type default)
			)
			(layer "B.SilkS")
		)
		(fp_line
			(start -1.524 -0.762)
			(end -1.524 0.762)
			(stroke
				(width 0.1524)
				(type default)
			)
			(layer "B.SilkS")
		)
		(fp_line
			(start 1.524 0.762)
			(end 1.524 -0.762)
			(stroke
				(width 0.1524)
				(type default)
			)
			(layer "B.SilkS")
		)
		(fp_line
			(start -1.524 0.762)
			(end 1.524 0.762)
			(stroke
				(width 0.1524)
				(type default)
			)
			(layer "B.SilkS")
		)
		(fp_line
			(start 1.1049 -0.724916)
			(end 1.1049 0.724916)
			(stroke
				(width 0.1)
				(type default)
			)
			(layer "B.Fab")
		)
		(fp_line
			(start -1.1049 -0.724916)
			(end 1.1049 -0.724916)
			(stroke
				(width 0.1)
				(type default)
			)
			(layer "B.Fab")
		)
		(fp_line
			(start 1.1049 0.724916)
			(end -1.1049 0.724916)
			(stroke
				(width 0.1)
				(type default)
			)
			(layer "B.Fab")
		)
		(fp_line
			(start -1.1049 0.724916)
			(end -1.1049 -0.724916)
			(stroke
				(width 0.1)
				(type default)
			)
			(layer "B.Fab")
		)
		(pad "1" smd rect
			(at 0.889 0 90)
			(size 1.016 1.27)
			(layers "B.Cu" "B.Mask" "B.Paste")
			(net "SW_P12V_PVCCFA_EHV_FIVRA_CPU1_R")
		)
		(pad "2" smd rect
			(at -0.889 0 90)
			(size 1.016 1.27)
			(layers "B.Cu" "B.Mask" "B.Paste")
			(net "GND")
		)
	)
	(footprint ""
		(layer "B.Cu")
		(at 105.13314 -415.323528 180)
		(property "Reference" "L20"
			(at 0 0 0)
			(layer "B.SilkS")
			(hide yes)
			(effects
				(font
					(size 1.27 1.27)
				)
				(justify mirror)
			)
		)
		(property "Value" ""
			(at 0 0 0)
			(layer "B.Fab")
			(effects
				(font
					(size 1.27 1.27)
				)
				(justify mirror)
			)
		)
		(duplicate_pad_numbers_are_jumpers no)
		(fp_line
			(start 1.63576 -0.8128)
			(end 1.63576 0.8128)
			(stroke
				(width 0.1524)
				(type default)
			)
			(layer "B.SilkS")
		)
		(fp_line
			(start 1.63576 -0.8128)
			(end -1.63576 -0.8128)
			(stroke
				(width 0.1524)
				(type default)
			)
			(layer "B.SilkS")
		)
		(fp_line
			(start -1.63576 0.8128)
			(end 1.63576 0.8128)
			(stroke
				(width 0.1524)
				(type default)
			)
			(layer "B.SilkS")
		)
		(fp_line
			(start -1.63576 -0.8128)
			(end -1.63576 0.8128)
			(stroke
				(width 0.1524)
				(type default)
			)
			(layer "B.SilkS")
		)
		(fp_line
			(start 1.56083 0.7366)
			(end 1.524 0.7366)
			(stroke
				(width 0.1)
				(type default)
			)
			(layer "B.Fab")
		)
		(fp_line
			(start 1.56083 -0.738632)
			(end 1.56083 0.7366)
			(stroke
				(width 0.1)
				(type default)
			)
			(layer "B.Fab")
		)
		(fp_line
			(start 1.524 0.7366)
			(end -1.524 0.7366)
			(stroke
				(width 0.1)
				(type default)
			)
			(layer "B.Fab")
		)
		(fp_line
			(start -1.524 0.7366)
			(end -1.560576 0.7366)
			(stroke
				(width 0.1)
				(type default)
			)
			(layer "B.Fab")
		)
		(fp_line
			(start -1.560576 0.7366)
			(end -1.560576 -0.738632)
			(stroke
				(width 0.1)
				(type default)
			)
			(layer "B.Fab")
		)
		(fp_line
			(start -1.560576 -0.738632)
			(end 1.56083 -0.738632)
			(stroke
				(width 0.1)
				(type default)
			)
			(layer "B.Fab")
		)
		(pad "1" smd rect
			(at 0.94996 0 180)
			(size 1.1176 1.3716)
			(layers "B.Cu" "B.Mask" "B.Paste")
			(net "P3V3")
		)
		(pad "2" smd rect
			(at -0.94996 0 180)
			(size 1.1176 1.3716)
			(layers "B.Cu" "B.Mask" "B.Paste")
			(net "P3V3_9ZXL045_VDD")
		)
	)
	(footprint ""
		(layer "B.Cu")
		(at 250.65482 -2.159)
		(property "Reference" "J68"
			(at 4.20751 1.143 270)
			(unlocked yes)
			(layer "B.SilkS")
			(effects
				(font
					(size 0.7874 0.5842)
					(thickness 0.1524)
				)
				(justify left mirror)
			)
		)
		(property "Value" ""
			(at 0 0 0)
			(layer "B.Fab")
			(effects
				(font
					(size 1.27 1.27)
				)
				(justify mirror)
			)
		)
		(duplicate_pad_numbers_are_jumpers no)
		(fp_line
			(start -1.2192 -2.1082)
			(end -1.2192 2.1082)
			(stroke
				(width 0.1524)
				(type default)
			)
			(layer "B.SilkS")
		)
		(fp_line
			(start -1.2192 2.1082)
			(end 1.2192 2.1082)
			(stroke
				(width 0.1524)
				(type default)
			)
			(layer "B.SilkS")
		)
		(fp_line
			(start 1.2192 -2.1082)
			(end -1.2192 -2.1082)
			(stroke
				(width 0.1524)
				(type default)
			)
			(layer "B.SilkS")
		)
		(fp_line
			(start 1.2192 2.1082)
			(end 1.2192 -2.1082)
			(stroke
				(width 0.1524)
				(type default)
			)
			(layer "B.SilkS")
		)
		(pad "" np_thru_hole circle
			(at -3.4671 -1.27 270)
			(size 1.0414 1.0414)
			(drill 1.0414)
			(layers "*.Cu" "*.Mask")
			(clearance 0.381)
			(thermal_gap 0.381)
		)
		(pad "" np_thru_hole circle
			(at -3.4671 1.27 270)
			(size 1.0414 1.0414)
			(drill 1.0414)
			(layers "*.Cu" "*.Mask")
			(clearance 0.381)
			(thermal_gap 0.381)
		)
		(pad "" np_thru_hole circle
			(at 2.8829 -1.27 270)
			(size 1.0414 1.0414)
			(drill 1.0414)
			(layers "*.Cu" "*.Mask")
			(clearance 0.381)
			(thermal_gap 0.381)
		)
		(pad "" np_thru_hole circle
			(at 2.8829 1.27 270)
			(size 1.0414 1.0414)
			(drill 1.0414)
			(layers "*.Cu" "*.Mask")
			(clearance 0.381)
			(thermal_gap 0.381)
		)
		(pad "1" smd rect
			(at -0.8255 -0.249936 270)
			(size 0.3048 0.508)
			(layers "B.Cu" "B.Mask" "B.Paste")
			(net "DELTA_L_85_5INCH_IN4_DP")
		)
		(pad "2" smd rect
			(at -0.8255 0.249936 270)
			(size 0.3048 0.508)
			(layers "B.Cu" "B.Mask" "B.Paste")
			(net "DELTA_L_85_5INCH_IN4_DN")
		)
		(pad "3" smd circle
			(at 0 0 180)
			(size 0 0)
			(layers "B.Cu" "B.Mask" "B.Paste")
			(net "DELTA_L_GND_1")
		)
		(zone
			(layers "F.Cu" "B.Cu" "In1.Cu" "In2.Cu" "In3.Cu" "In4.Cu" "In5.Cu" "In6.Cu"
				"In7.Cu" "In8.Cu" "In9.Cu" "In10.Cu" "In11.Cu" "In12.Cu" "In13.Cu" "In14.Cu"
				"In15.Cu" "In16.Cu"
			)
			(hatch none 0.5)
			(connect_pads
				(clearance 0)
			)
			(min_thickness 0.25)
			(keepout
				(tracks not_allowed)
				(vias allowed)
				(pads allowed)
				(copperpour not_allowed)
				(footprints allowed)
			)
			(placement
				(enabled no)
				(sheetname "")
			)
			(fill
				(thermal_gap 0.5)
				(thermal_bridge_width 0.5)
				(island_removal_mode 0)
			)
			(polygon
				(pts
					(arc
						(start 248.11482 -3.429)
						(mid 246.26062 -3.429)
						(end 248.11482 -3.429)
					)
				)
			)
		)
		(zone
			(layers "F.Cu" "B.Cu" "In1.Cu" "In2.Cu" "In3.Cu" "In4.Cu" "In5.Cu" "In6.Cu"
				"In7.Cu" "In8.Cu" "In9.Cu" "In10.Cu" "In11.Cu" "In12.Cu" "In13.Cu" "In14.Cu"
				"In15.Cu" "In16.Cu"
			)
			(hatch none 0.5)
			(connect_pads
				(clearance 0)
			)
			(min_thickness 0.25)
			(keepout
				(tracks not_allowed)
				(vias allowed)
				(pads allowed)
				(copperpour not_allowed)
				(footprints allowed)
			)
			(placement
				(enabled no)
				(sheetname "")
			)
			(fill
				(thermal_gap 0.5)
				(thermal_bridge_width 0.5)
				(island_removal_mode 0)
			)
			(polygon
				(pts
					(arc
						(start 248.11482 -0.889)
						(mid 246.26062 -0.889)
						(end 248.11482 -0.889)
					)
				)
			)
		)
		(zone
			(layers "F.Cu" "B.Cu" "In1.Cu" "In2.Cu" "In3.Cu" "In4.Cu" "In5.Cu" "In6.Cu"
				"In7.Cu" "In8.Cu" "In9.Cu" "In10.Cu" "In11.Cu" "In12.Cu" "In13.Cu" "In14.Cu"
				"In15.Cu" "In16.Cu"
			)
			(hatch none 0.5)
			(connect_pads
				(clearance 0)
			)
			(min_thickness 0.25)
			(keepout
				(tracks not_allowed)
				(vias allowed)
				(pads allowed)
				(copperpour not_allowed)
				(footprints allowed)
			)
			(placement
				(enabled no)
				(sheetname "")
			)
			(fill
				(thermal_gap 0.5)
				(thermal_bridge_width 0.5)
				(island_removal_mode 0)
			)
			(polygon
				(pts
					(arc
						(start 254.46482 -3.429)
						(mid 252.61062 -3.429)
						(end 254.46482 -3.429)
					)
				)
			)
		)
		(zone
			(layers "F.Cu" "B.Cu" "In1.Cu" "In2.Cu" "In3.Cu" "In4.Cu" "In5.Cu" "In6.Cu"
				"In7.Cu" "In8.Cu" "In9.Cu" "In10.Cu" "In11.Cu" "In12.Cu" "In13.Cu" "In14.Cu"
				"In15.Cu" "In16.Cu"
			)
			(hatch none 0.5)
			(connect_pads
				(clearance 0)
			)
			(min_thickness 0.25)
			(keepout
				(tracks not_allowed)
				(vias allowed)
				(pads allowed)
				(copperpour not_allowed)
				(footprints allowed)
			)
			(placement
				(enabled no)
				(sheetname "")
			)
			(fill
				(thermal_gap 0.5)
				(thermal_bridge_width 0.5)
				(island_removal_mode 0)
			)
			(polygon
				(pts
					(arc
						(start 254.46482 -0.889)
						(mid 252.61062 -0.889)
						(end 254.46482 -0.889)
					)
				)
			)
		)
		(zone
			(layer "B.Cu")
			(hatch none 0.5)
			(connect_pads
				(clearance 0)
			)
			(min_thickness 0.25)
			(keepout
				(tracks not_allowed)
				(vias allowed)
				(pads allowed)
				(copperpour not_allowed)
				(footprints allowed)
			)
			(placement
				(enabled no)
				(sheetname "")
			)
			(fill
				(thermal_gap 0.5)
				(thermal_bridge_width 0.5)
				(island_removal_mode 0)
			)
			(polygon
				(pts
					(xy 249.53722 -2.70764) (xy 249.53722 -2.612136) (xy 250.13412 -2.612136) (xy 250.13412 -2.205736)
					(xy 249.53722 -2.205736) (xy 249.53722 -2.112264) (xy 250.13412 -2.112264) (xy 250.13412 -1.705864)
					(xy 249.53722 -1.705864) (xy 249.53722 -1.61036) (xy 250.23572 -1.61036) (xy 250.23572 -2.70764)
				)
			)
		)
	)
	(footprint ""
		(layer "B.Cu")
		(at 263.064752 -99.450398 -90)
		(property "Reference" "R1527"
			(at 0 0 90)
			(layer "B.SilkS")
			(hide yes)
			(effects
				(font
					(size 1.27 1.27)
				)
				(justify mirror)
			)
		)
		(property "Value" ""
			(at 0 0 90)
			(layer "B.Fab")
			(effects
				(font
					(size 1.27 1.27)
				)
				(justify mirror)
			)
		)
		(duplicate_pad_numbers_are_jumpers no)
		(fp_line
			(start -0.7874 0.4064)
			(end 0.7874 0.4064)
			(stroke
				(width 0.1524)
				(type default)
			)
			(layer "B.SilkS")
		)
		(fp_line
			(start 0.7874 0.4064)
			(end 0.7874 -0.4064)
			(stroke
				(width 0.1524)
				(type default)
			)
			(layer "B.SilkS")
		)
		(fp_line
			(start -0.7874 -0.4064)
			(end -0.7874 0.4064)
			(stroke
				(width 0.1524)
				(type default)
			)
			(layer "B.SilkS")
		)
		(fp_line
			(start 0.7874 -0.4064)
			(end -0.7874 -0.4064)
			(stroke
				(width 0.1524)
				(type default)
			)
			(layer "B.SilkS")
		)
		(fp_line
			(start -0.67945 0.3048)
			(end -0.120396 0.3048)
			(stroke
				(width 0.1)
				(type default)
			)
			(layer "B.Fab")
		)
		(fp_line
			(start -0.120396 0.3048)
			(end -0.120396 0.2794)
			(stroke
				(width 0.1)
				(type default)
			)
			(layer "B.Fab")
		)
		(fp_line
			(start 0.12065 0.3048)
			(end 0.67945 0.3048)
			(stroke
				(width 0.1)
				(type default)
			)
			(layer "B.Fab")
		)
		(fp_line
			(start 0.67945 0.3048)
			(end 0.67945 -0.305054)
			(stroke
				(width 0.1)
				(type default)
			)
			(layer "B.Fab")
		)
		(fp_line
			(start -0.120396 0.2794)
			(end 0.12065 0.2794)
			(stroke
				(width 0.1)
				(type default)
			)
			(layer "B.Fab")
		)
		(fp_line
			(start 0.12065 0.2794)
			(end 0.12065 0.3048)
			(stroke
				(width 0.1)
				(type default)
			)
			(layer "B.Fab")
		)
		(fp_line
			(start -0.12065 -0.2794)
			(end -0.12065 -0.3048)
			(stroke
				(width 0.1)
				(type default)
			)
			(layer "B.Fab")
		)
		(fp_line
			(start 0.12065 -0.2794)
			(end -0.12065 -0.2794)
			(stroke
				(width 0.1)
				(type default)
			)
			(layer "B.Fab")
		)
		(fp_line
			(start -0.67945 -0.3048)
			(end -0.67945 0.3048)
			(stroke
				(width 0.1)
				(type default)
			)
			(layer "B.Fab")
		)
		(fp_line
			(start -0.12065 -0.3048)
			(end -0.67945 -0.3048)
			(stroke
				(width 0.1)
				(type default)
			)
			(layer "B.Fab")
		)
		(fp_line
			(start 0.12065 -0.305054)
			(end 0.12065 -0.2794)
			(stroke
				(width 0.1)
				(type default)
			)
			(layer "B.Fab")
		)
		(fp_line
			(start 0.67945 -0.305054)
			(end 0.12065 -0.305054)
			(stroke
				(width 0.1)
				(type default)
			)
			(layer "B.Fab")
		)
		(pad "1" smd circle
			(at 0.40005 0 90)
			(size 0 0)
			(layers "B.Cu" "B.Mask" "B.Paste")
			(net "FM_CLK_GEN1_OE0_N")
		)
		(pad "2" smd circle
			(at -0.40005 0 90)
			(size 0 0)
			(layers "B.Cu" "B.Mask" "B.Paste")
			(net "GND")
		)
	)
	(footprint ""
		(layer "B.Cu")
		(at 292.998398 -153.546048 -90)
		(property "Reference" "R683"
			(at 0 0 90)
			(layer "B.SilkS")
			(hide yes)
			(effects
				(font
					(size 1.27 1.27)
				)
				(justify mirror)
			)
		)
		(property "Value" ""
			(at 0 0 90)
			(layer "B.Fab")
			(effects
				(font
					(size 1.27 1.27)
				)
				(justify mirror)
			)
		)
		(duplicate_pad_numbers_are_jumpers no)
		(fp_line
			(start -0.7874 0.4064)
			(end 0.7874 0.4064)
			(stroke
				(width 0.1524)
				(type default)
			)
			(layer "B.SilkS")
		)
		(fp_line
			(start 0.7874 0.4064)
			(end 0.7874 -0.4064)
			(stroke
				(width 0.1524)
				(type default)
			)
			(layer "B.SilkS")
		)
		(fp_line
			(start -0.7874 -0.4064)
			(end -0.7874 0.4064)
			(stroke
				(width 0.1524)
				(type default)
			)
			(layer "B.SilkS")
		)
		(fp_line
			(start 0.7874 -0.4064)
			(end -0.7874 -0.4064)
			(stroke
				(width 0.1524)
				(type default)
			)
			(layer "B.SilkS")
		)
		(fp_line
			(start -0.67945 0.3048)
			(end -0.120396 0.3048)
			(stroke
				(width 0.1)
				(type default)
			)
			(layer "B.Fab")
		)
		(fp_line
			(start -0.120396 0.3048)
			(end -0.120396 0.2794)
			(stroke
				(width 0.1)
				(type default)
			)
			(layer "B.Fab")
		)
		(fp_line
			(start 0.12065 0.3048)
			(end 0.67945 0.3048)
			(stroke
				(width 0.1)
				(type default)
			)
			(layer "B.Fab")
		)
		(fp_line
			(start 0.67945 0.3048)
			(end 0.67945 -0.305054)
			(stroke
				(width 0.1)
				(type default)
			)
			(layer "B.Fab")
		)
		(fp_line
			(start -0.120396 0.2794)
			(end 0.12065 0.2794)
			(stroke
				(width 0.1)
				(type default)
			)
			(layer "B.Fab")
		)
		(fp_line
			(start 0.12065 0.2794)
			(end 0.12065 0.3048)
			(stroke
				(width 0.1)
				(type default)
			)
			(layer "B.Fab")
		)
		(fp_line
			(start -0.12065 -0.2794)
			(end -0.12065 -0.3048)
			(stroke
				(width 0.1)
				(type default)
			)
			(layer "B.Fab")
		)
		(fp_line
			(start 0.12065 -0.2794)
			(end -0.12065 -0.2794)
			(stroke
				(width 0.1)
				(type default)
			)
			(layer "B.Fab")
		)
		(fp_line
			(start -0.67945 -0.3048)
			(end -0.67945 0.3048)
			(stroke
				(width 0.1)
				(type default)
			)
			(layer "B.Fab")
		)
		(fp_line
			(start -0.12065 -0.3048)
			(end -0.67945 -0.3048)
			(stroke
				(width 0.1)
				(type default)
			)
			(layer "B.Fab")
		)
		(fp_line
			(start 0.12065 -0.305054)
			(end 0.12065 -0.2794)
			(stroke
				(width 0.1)
				(type default)
			)
			(layer "B.Fab")
		)
		(fp_line
			(start 0.67945 -0.305054)
			(end 0.12065 -0.305054)
			(stroke
				(width 0.1)
				(type default)
			)
			(layer "B.Fab")
		)
		(pad "1" smd circle
			(at 0.40005 0 90)
			(size 0 0)
			(layers "B.Cu" "B.Mask" "B.Paste")
			(net "I3C_SPD_DDRABCD_CPU0_R_SDA")
		)
		(pad "2" smd circle
			(at -0.40005 0 90)
			(size 0 0)
			(layers "B.Cu" "B.Mask" "B.Paste")
			(net "I3C_SPD_DDRABCD_CPU0_LVC1_R_SDA")
		)
	)
	(footprint ""
		(layer "B.Cu")
		(at 369.49888 -45.176948 180)
		(property "Reference" "R4113"
			(at 0 0 0)
			(layer "B.SilkS")
			(hide yes)
			(effects
				(font
					(size 1.27 1.27)
				)
				(justify mirror)
			)
		)
		(property "Value" ""
			(at 0 0 0)
			(layer "B.Fab")
			(effects
				(font
					(size 1.27 1.27)
				)
				(justify mirror)
			)
		)
		(duplicate_pad_numbers_are_jumpers no)
		(fp_line
			(start 0.7874 0.4064)
			(end 0.7874 -0.4064)
			(stroke
				(width 0.1524)
				(type default)
			)
			(layer "B.SilkS")
		)
		(fp_line
			(start 0.7874 -0.4064)
			(end -0.7874 -0.4064)
			(stroke
				(width 0.1524)
				(type default)
			)
			(layer "B.SilkS")
		)
		(fp_line
			(start -0.7874 0.4064)
			(end 0.7874 0.4064)
			(stroke
				(width 0.1524)
				(type default)
			)
			(layer "B.SilkS")
		)
		(fp_line
			(start -0.7874 -0.4064)
			(end -0.7874 0.4064)
			(stroke
				(width 0.1524)
				(type default)
			)
			(layer "B.SilkS")
		)
		(fp_line
			(start 0.67945 0.3048)
			(end 0.67945 -0.305054)
			(stroke
				(width 0.1)
				(type default)
			)
			(layer "B.Fab")
		)
		(fp_line
			(start 0.67945 -0.305054)
			(end 0.12065 -0.305054)
			(stroke
				(width 0.1)
				(type default)
			)
			(layer "B.Fab")
		)
		(fp_line
			(start 0.12065 0.3048)
			(end 0.67945 0.3048)
			(stroke
				(width 0.1)
				(type default)
			)
			(layer "B.Fab")
		)
		(fp_line
			(start 0.12065 0.2794)
			(end 0.12065 0.3048)
			(stroke
				(width 0.1)
				(type default)
			)
			(layer "B.Fab")
		)
		(fp_line
			(start 0.12065 -0.2794)
			(end -0.12065 -0.2794)
			(stroke
				(width 0.1)
				(type default)
			)
			(layer "B.Fab")
		)
		(fp_line
			(start 0.12065 -0.305054)
			(end 0.12065 -0.2794)
			(stroke
				(width 0.1)
				(type default)
			)
			(layer "B.Fab")
		)
		(fp_line
			(start -0.120396 0.3048)
			(end -0.120396 0.2794)
			(stroke
				(width 0.1)
				(type default)
			)
			(layer "B.Fab")
		)
		(fp_line
			(start -0.120396 0.2794)
			(end 0.12065 0.2794)
			(stroke
				(width 0.1)
				(type default)
			)
			(layer "B.Fab")
		)
		(fp_line
			(start -0.12065 -0.2794)
			(end -0.12065 -0.3048)
			(stroke
				(width 0.1)
				(type default)
			)
			(layer "B.Fab")
		)
		(fp_line
			(start -0.12065 -0.3048)
			(end -0.67945 -0.3048)
			(stroke
				(width 0.1)
				(type default)
			)
			(layer "B.Fab")
		)
		(fp_line
			(start -0.67945 0.3048)
			(end -0.120396 0.3048)
			(stroke
				(width 0.1)
				(type default)
			)
			(layer "B.Fab")
		)
		(fp_line
			(start -0.67945 -0.3048)
			(end -0.67945 0.3048)
			(stroke
				(width 0.1)
				(type default)
			)
			(layer "B.Fab")
		)
		(pad "1" smd circle
			(at 0.40005 0)
			(size 0 0)
			(layers "B.Cu" "B.Mask" "B.Paste")
			(net "PD_PCH_GPP_E_11")
		)
		(pad "2" smd circle
			(at -0.40005 0)
			(size 0 0)
			(layers "B.Cu" "B.Mask" "B.Paste")
			(net "GND")
		)
	)
)
